# S9S_MB_2U (Grand Teton) — schematic netlist excerpt (pin names and nets, part order shuffled) for the footprints in the layout excerpt that follows; sources: Cadence DE-HDL packaged netlist, KiCad conversion of 03242023_DA0F0TMBIJ0_F0T_Motherboard_J_brd_V01_OCP.brd

C142  Q_CAP_DIFFBUS  DIFF BUS_0.22UF 6.3V 20% X6S  pkg C0201  page 178 : \1\ = DMI_CPU0_PCH_TX_C_DP<6> ; \2\ = DMI_CPU0_PCH_TX_DP<6>
PC238  Q_CAP  680PF 50V 10% X7R  pkg 0402  page 300 : A = PVNN_MAIN_CPU1_FB ; B = PVNN_MAIN_CPU1_FB_RC

(kicad_pcb
	(version 20260206)
	(generator "pcbnew")
	(generator_version "10.0")
	(general
		(thickness 1.6)
		(legacy_teardrops no)
	)
	(paper "A4")
	(title_block
		(title "03242023_DA0F0TMBIJ0_F0T_Motherboard_J_brd_V01_OCP.brd")
		(comment 1 "Grand Teton / footprints 3556-3557 of 6105")
	)
	(layers
		(0 "F.Cu" signal "TOP")
		(4 "In1.Cu" signal "GND")
		(6 "In2.Cu" signal "IN1")
		(8 "In3.Cu" signal "GND1")
		(10 "In4.Cu" signal "IN2")
		(12 "In5.Cu" signal "GND2")
		(14 "In6.Cu" signal "IN3")
		(16 "In7.Cu" signal "GND3")
		(18 "In8.Cu" signal "VCC")
		(20 "In9.Cu" signal "VCC1")
		(22 "In10.Cu" signal "GND4")
		(24 "In11.Cu" signal "IN4")
		(26 "In12.Cu" signal "GND5")
		(28 "In13.Cu" signal "IN5")
		(30 "In14.Cu" signal "GND6")
		(32 "In15.Cu" signal "IN6")
		(34 "In16.Cu" signal "GND7")
		(2 "B.Cu" signal "BOTTOM")
		(9 "F.Adhes" user "F.Adhesive")
		(11 "B.Adhes" user "B.Adhesive")
		(13 "F.Paste" user "Package Geometry/Pastemask Top")
		(15 "B.Paste" user "Package Geometry/Pastemask Bottom")
		(5 "F.SilkS" user "Ref Des/Silkscreen Top")
		(7 "B.SilkS" user "Ref Des/Silkscreen Bottom")
		(1 "F.Mask" user "Board Geometry/Soldermask Top")
		(3 "B.Mask" user "Board Geometry/Soldermask Bottom")
		(17 "Dwgs.User" user "User.Drawings")
		(19 "Cmts.User" user "User.Comments")
		(21 "Eco1.User" user "User.Eco1")
		(23 "Eco2.User" user "User.Eco2")
		(25 "Edge.Cuts" user "Board Geometry/Outline")
		(27 "Margin" user)
		(31 "F.CrtYd" user "Package Geometry/Place Bound Top")
		(29 "B.CrtYd" user "Package Geometry/Place Bound Bottom")
		(35 "F.Fab" user "Ref Des/Assembly Top")
		(33 "B.Fab" user "Ref Des/Assembly Bottom")
	)
	(footprint ""
		(layer "F.Cu")
		(at 349.0849 -63.312548)
		(property "Reference" "C142"
			(at 0 0 0)
			(layer "F.SilkS")
			(hide yes)
			(effects
				(font
					(size 1.27 1.27)
				)
			)
		)
		(property "Value" ""
			(at 0 0 0)
			(layer "F.Fab")
			(effects
				(font
					(size 1.27 1.27)
				)
			)
		)
		(duplicate_pad_numbers_are_jumpers no)
		(fp_line
			(start -0.299974 -0.150114)
			(end 0.299974 -0.150114)
			(stroke
				(width 0.1)
				(type default)
			)
			(layer "F.Fab")
		)
		(fp_line
			(start -0.299974 0.150114)
			(end -0.299974 -0.150114)
			(stroke
				(width 0.1)
				(type default)
			)
			(layer "F.Fab")
		)
		(fp_line
			(start 0.299974 -0.150114)
			(end 0.299974 0.150114)
			(stroke
				(width 0.1)
				(type default)
			)
			(layer "F.Fab")
		)
		(fp_line
			(start 0.299974 0.150114)
			(end -0.299974 0.150114)
			(stroke
				(width 0.1)
				(type default)
			)
			(layer "F.Fab")
		)
		(pad "1" smd rect
			(at -0.2667 0)
			(size 0.3048 0.381)
			(layers "F.Cu" "F.Mask" "F.Paste")
			(net "DMI_CPU0_PCH_TX_C_DP<6>")
		)
		(pad "2" smd rect
			(at 0.2667 0)
			(size 0.3048 0.381)
			(layers "F.Cu" "F.Mask" "F.Paste")
			(net "DMI_CPU0_PCH_TX_DP<6>")
		)
		(zone
			(layer "In1.Cu")
			(hatch none 0.5)
			(connect_pads
				(clearance 0)
			)
			(min_thickness 0.25)
			(keepout
				(tracks not_allowed)
				(vias allowed)
				(pads allowed)
				(copperpour not_allowed)
				(footprints allowed)
			)
			(placement
				(enabled no)
				(sheetname "")
			)
			(fill
				(thermal_gap 0.5)
				(thermal_bridge_width 0.5)
				(island_removal_mode 0)
			)
			(polygon
				(pts
					(arc
						(start 348.6912 -63.071248)
						(mid 348.637318 -63.093566)
						(end 348.615 -63.147448)
					)
					(arc
						(start 348.615 -63.477648)
						(mid 348.637318 -63.53153)
						(end 348.6912 -63.553848)
					)
					(arc
						(start 348.9452 -63.553848)
						(mid 348.999082 -63.53153)
						(end 349.0214 -63.477648)
					)
					(arc
						(start 349.0214 -63.147448)
						(mid 348.999082 -63.093566)
						(end 348.9452 -63.071248)
					)
				)
			)
		)
		(zone
			(layer "In1.Cu")
			(hatch none 0.5)
			(connect_pads
				(clearance 0)
			)
			(min_thickness 0.25)
			(keepout
				(tracks not_allowed)
				(vias allowed)
				(pads allowed)
				(copperpour not_allowed)
				(footprints allowed)
			)
			(placement
				(enabled no)
				(sheetname "")
			)
			(fill
				(thermal_gap 0.5)
				(thermal_bridge_width 0.5)
				(island_removal_mode 0)
			)
			(polygon
				(pts
					(arc
						(start 349.2246 -63.071248)
						(mid 349.170718 -63.093566)
						(end 349.1484 -63.147448)
					)
					(arc
						(start 349.1484 -63.477648)
						(mid 349.170718 -63.53153)
						(end 349.2246 -63.553848)
					)
					(arc
						(start 349.4786 -63.553848)
						(mid 349.532482 -63.53153)
						(end 349.5548 -63.477648)
					)
					(arc
						(start 349.5548 -63.147448)
						(mid 349.532482 -63.093566)
						(end 349.4786 -63.071248)
					)
				)
			)
		)
	)
	(footprint ""
		(layer "F.Cu")
		(at 22.356826 -174.113952)
		(property "Reference" "PC238"
			(at 0 0 0)
			(layer "F.SilkS")
			(hide yes)
			(effects
				(font
					(size 1.27 1.27)
				)
			)
		)
		(property "Value" ""
			(at 0 0 0)
			(layer "F.Fab")
			(effects
				(font
					(size 1.27 1.27)
				)
			)
		)
		(duplicate_pad_numbers_are_jumpers no)
		(fp_line
			(start -0.7874 -0.4064)
			(end 0.7874 -0.4064)
			(stroke
				(width 0.1524)
				(type default)
			)
			(layer "F.SilkS")
		)
		(fp_line
			(start -0.7874 0.4064)
			(end -0.7874 -0.4064)
			(stroke
				(width 0.1524)
				(type default)
			)
			(layer "F.SilkS")
		)
		(fp_line
			(start 0.7874 -0.4064)
			(end 0.7874 0.4064)
			(stroke
				(width 0.1524)
				(type default)
			)
			(layer "F.SilkS")
		)
		(fp_line
			(start 0.7874 0.4064)
			(end -0.7874 0.4064)
			(stroke
				(width 0.1524)
				(type default)
			)
			(layer "F.SilkS")
		)
		(fp_line
			(start -0.67945 -0.305054)
			(end -0.12065 -0.305054)
			(stroke
				(width 0.1)
				(type default)
			)
			(layer "F.Fab")
		)
		(fp_line
			(start -0.67945 0.3048)
			(end -0.67945 -0.305054)
			(stroke
				(width 0.1)
				(type default)
			)
			(layer "F.Fab")
		)
		(fp_line
			(start -0.12065 -0.305054)
			(end -0.12065 -0.2794)
			(stroke
				(width 0.1)
				(type default)
			)
			(layer "F.Fab")
		)
		(fp_line
			(start -0.12065 -0.2794)
			(end 0.12065 -0.2794)
			(stroke
				(width 0.1)
				(type default)
			)
			(layer "F.Fab")
		)
		(fp_line
			(start -0.12065 0.2794)
			(end -0.12065 0.3048)
			(stroke
				(width 0.1)
				(type default)
			)
			(layer "F.Fab")
		)
		(fp_line
			(start -0.12065 0.3048)
			(end -0.67945 0.3048)
			(stroke
				(width 0.1)
				(type default)
			)
			(layer "F.Fab")
		)
		(fp_line
			(start 0.120396 0.2794)
			(end -0.12065 0.2794)
			(stroke
				(width 0.1)
				(type default)
			)
			(layer "F.Fab")
		)
		(fp_line
			(start 0.120396 0.3048)
			(end 0.120396 0.2794)
			(stroke
				(width 0.1)
				(type default)
			)
			(layer "F.Fab")
		)
		(fp_line
			(start 0.12065 -0.3048)
			(end 0.67945 -0.3048)
			(stroke
				(width 0.1)
				(type default)
			)
			(layer "F.Fab")
		)
		(fp_line
			(start 0.12065 -0.2794)
			(end 0.12065 -0.3048)
			(stroke
				(width 0.1)
				(type default)
			)
			(layer "F.Fab")
		)
		(fp_line
			(start 0.67945 -0.3048)
			(end 0.67945 0.3048)
			(stroke
				(width 0.1)
				(type default)
			)
			(layer "F.Fab")
		)
		(fp_line
			(start 0.67945 0.3048)
			(end 0.120396 0.3048)
			(stroke
				(width 0.1)
				(type default)
			)
			(layer "F.Fab")
		)
		(pad "1" smd circle
			(at -0.40005 0)
			(size 0 0)
			(layers "F.Cu" "F.Mask" "F.Paste")
			(net "PVNN_MAIN_CPU1_FB")
		)
		(pad "2" smd circle
			(at 0.40005 0)
			(size 0 0)
			(layers "F.Cu" "F.Mask" "F.Paste")
			(net "PVNN_MAIN_CPU1_FB_RC")
		)
	)
)
